# BOM_M2_NEO-M9N_MODULE.xlsx — BOM_M2_NEO-M9N_MODULE (bom)
| Comment | Description | Designator | Footprint | LibRef | Quantity | Digi-Key_Part_Number_1 | Digi-Key_Part_Number_2 | Digi-Key_Part_Number_3 | Manufacturer Part Number | Manufacturer Part Number 1 | Manufacturer_Part_Number |
| 1uF 6V3 0402 | 0402 1 uF 6.3 V ±10% Tolerance X7R Multilayer Ceramic Capacitor | C1 | c0402 | CAP CER 1UF 6.3V X7R 0402 | 1 |  |  |  | GRM155R70J105KA12J |  |  |
| 100nF 10V 0402 | CL05 Series 0.1 uF 10 V ±10 % Tolerance X7R SMT Multilayer Ceramic Capacitor | C2 | c0402 | CAP CER 0.1UF 10V X7R 0402 | 1 |  |  |  | CL05B104KP5NNNC |  |  |
| 10nF 50V 0402 | CAP CER 10000PF 50V X7R 0402 | C3, C5 | c0402 | CAP CER 10000PF 50V X7R 0402 | 2 |  |  |  | GCM155R71H103KA55D |  |  |
| 47pF 50V 0402 | 0402 47 pF 50 V ±5 % Tolerance NP0 SMT Multilayer Ceramic Capacitor | C4 | c0402 | CAP CER 47PF 50V C0G/NPO 0402 | 1 |  |  |  | CC0402JRNPO9BN470 |  |  |
| 47uF_6.3V_1206 | Chip Multilayer Ceramic Capacitors for General Purpose, 1206, 47uF, X5R, 15%, 20%, 6.3V | C6, C7 | FP-GRM31C-0_2-e0_3_0_8-IPC_C | CMP-2000-06344-2 | 2 |  |  |  |  |  |  |
| U.FL-R-SMT-1(10) | CONN U.FL RCPT STR 50 OHM SMD | J2 | FP-U_FL-R-SMT-1_10-MFG | CMP-2000-05152-3 | 1 |  |  |  |  |  |  |
| 27nH 350mA 0.46ohm 0402 | Multilayer type RF Inductor 27nH ±5% 0.46Ω 350mA 0402 | L1 | FP-LQG15HH_02-IPC_C | CMP-2000-06578-2 | 1 |  |  |  | LQG15HS27NJ02D |  |  |
| Green | LED High-Power Uni-Color Green 574nm 2-Pin Chip LED T/R | LED1, LED2 | led0603 | LED GREEN CLEAR CHIP SMD | 2 |  |  |  | LTST-C190KGKT |  |  |
| DMG2302UKQ-7 | N-Channel 20 V 2.8A (Ta) 660mW (Ta) Surface Mount SOT-23-3 | Q1 | SOT23 | DMG2302UKQ-7 | 1 | 31-DMG2302UKQ-7TR-ND | 31-DMG2302UKQ-7CT-ND | 31-DMG2302UKQ-7DKR-ND | DMG2302UKQ-7 |  | DMG2302UKQ-7 |
| 2N7002W | MOSFET N-CH 60V 115MA SOT-323 | Q2 | FP-419AB-01-IPC_C | CMP-07173-000098-1 | 1 |  |  |  |  |  |  |
| 0 ohm 0402 | RES SMD 0 OHM JUMPER 1/16W 0402 | R1, R5, R7, R8 | r0402 | RES 0 OHM JUMPER 1/16W 0402 | 4 |  |  |  | RC0402JR-070RL |  |  |
| 10K_5%_0402 |  | R2, R11 | RESC1005X40X25LL05T10 | CMP-2002-07353-1 | 2 |  |  |  |  |  |  |
| 1K_1%_0402 | Chip Resistor, 1 KOhm, +/- 1%, 100 mW, -55 to 155 degC, 0402 (1005 Metric), RoHS, Tape and Reel | R3, R16 | RESC1005X40X25NL05T05 | CMP-1011-00510-4 | 2 |  |  |  |  |  |  |
| 10 OHM 1/4W 0603 | Res Surge Chip Thick Film 0603 10 Ohm 1% 1/4W ±200ppm/°C Molded Paper T/R | R4 | r0603 | RES SMD 10 OHM 1% 1/4W 0603 | 1 |  |  |  | SR0603FR-7T10RL |  |  |
| 0_5%_0402 |  | R12, R13, R15 | RESC1005X40X25NL05T10 | CMP-2002-06457-1 | 3 |  |  |  |  |  |  |
| NEO-M9N-00B | GNSS module, Flash, TCXO, SAW, LNA, LCC, 12x16 mm Professional Grade | U1 | IC_NEO-M9N | IC NEO-M9N-00B | 1 |  |  |  | NEO-M9N-00B |  |  |
